# T6G (Grand Teton) — schematic netlist excerpt (pin names and nets, part order shuffled) for the footprints in the layout excerpt that follows; sources: Cadence DE-HDL packaged netlist, KiCad conversion of 04192023_DAF0TMB3IC0_F0TG_MB_C_brd_V02_OCP.brd

PR8389  Q_RES  1 1% CHIP  pkg 0402LF  page 190 : A = P3V3_AUX_VDRV ; B = P3V3_AUX_VCC
R1120  Q_RES  4.7K 5% CHIP  pkg 0201LF  page 309 : A = TEST2_RT_CPU0_P3 ; B = GND
PC1847  Q_CAP  0.22UF 25V 10% X7R  pkg C0402  page 189 : A = SW_P5V_AUX_BST ; B = SW_P5V_AUX_SW

(kicad_pcb
	(version 20260206)
	(generator "pcbnew")
	(generator_version "10.0")
	(general
		(thickness 1.6)
		(legacy_teardrops no)
	)
	(paper "A4")
	(title_block
		(title "04192023_DAF0TMB3IC0_F0TG_MB_C_brd_V02_OCP.brd")
		(comment 1 "Grand Teton / footprints 170-172 of 8354")
	)
	(layers
		(0 "F.Cu" signal "TOP")
		(4 "In1.Cu" signal "GND")
		(6 "In2.Cu" signal "IN1")
		(8 "In3.Cu" signal "GND1")
		(10 "In4.Cu" signal "IN2")
		(12 "In5.Cu" signal "GND2")
		(14 "In6.Cu" signal "IN3")
		(16 "In7.Cu" signal "GND3")
		(18 "In8.Cu" signal "VCC")
		(20 "In9.Cu" signal "VCC1")
		(22 "In10.Cu" signal "GND4")
		(24 "In11.Cu" signal "IN4")
		(26 "In12.Cu" signal "GND5")
		(28 "In13.Cu" signal "IN5")
		(30 "In14.Cu" signal "GND6")
		(32 "In15.Cu" signal "IN6")
		(34 "In16.Cu" signal "GND7")
		(2 "B.Cu" signal "BOTTOM")
		(9 "F.Adhes" user "F.Adhesive")
		(11 "B.Adhes" user "B.Adhesive")
		(13 "F.Paste" user "Package Geometry/Pastemask Top")
		(15 "B.Paste" user "Package Geometry/Pastemask Bottom")
		(5 "F.SilkS" user "Ref Des/Silkscreen Top")
		(7 "B.SilkS" user "Ref Des/Silkscreen Bottom")
		(1 "F.Mask" user "Board Geometry/Soldermask Top")
		(3 "B.Mask" user "Board Geometry/Soldermask Bottom")
		(17 "Dwgs.User" user "User.Drawings")
		(19 "Cmts.User" user "User.Comments")
		(21 "Eco1.User" user "User.Eco1")
		(23 "Eco2.User" user "User.Eco2")
		(25 "Edge.Cuts" user "Board Geometry/Outline")
		(27 "Margin" user)
		(31 "F.CrtYd" user "Package Geometry/Place Bound Top")
		(29 "B.CrtYd" user "Package Geometry/Place Bound Bottom")
		(35 "F.Fab" user "Ref Des/Assembly Top")
		(33 "B.Fab" user "Ref Des/Assembly Bottom")
	)
	(footprint ""
		(layer "F.Cu")
		(at 366.36579 -392.1252)
		(property "Reference" "R1120"
			(at 0 0 0)
			(layer "F.SilkS")
			(hide yes)
			(effects
				(font
					(size 1.27 1.27)
				)
			)
		)
		(property "Value" ""
			(at 0 0 0)
			(layer "F.Fab")
			(effects
				(font
					(size 1.27 1.27)
				)
			)
		)
		(duplicate_pad_numbers_are_jumpers no)
		(fp_line
			(start -0.32512 -0.175006)
			(end 0.32512 -0.175006)
			(stroke
				(width 0.1)
				(type default)
			)
			(layer "F.Fab")
		)
		(fp_line
			(start -0.32512 0.175006)
			(end -0.32512 -0.175006)
			(stroke
				(width 0.1)
				(type default)
			)
			(layer "F.Fab")
		)
		(fp_line
			(start 0.32512 -0.175006)
			(end 0.32512 0.175006)
			(stroke
				(width 0.1)
				(type default)
			)
			(layer "F.Fab")
		)
		(fp_line
			(start 0.32512 0.175006)
			(end -0.32512 0.175006)
			(stroke
				(width 0.1)
				(type default)
			)
			(layer "F.Fab")
		)
		(pad "1" smd rect
			(at -0.2667 0)
			(size 0.3048 0.381)
			(layers "F.Cu" "F.Mask" "F.Paste")
			(net "TEST2_RT_CPU0_P3")
		)
		(pad "2" smd rect
			(at 0.2667 0 180)
			(size 0.3048 0.381)
			(layers "F.Cu" "F.Mask" "F.Paste")
			(net "GND")
		)
	)
	(footprint ""
		(layer "F.Cu")
		(at 410.846524 -143.872204 90)
		(property "Reference" "PC1847"
			(at 0 0 90)
			(layer "F.SilkS")
			(hide yes)
			(effects
				(font
					(size 1.27 1.27)
				)
			)
		)
		(property "Value" ""
			(at 0 0 90)
			(layer "F.Fab")
			(effects
				(font
					(size 1.27 1.27)
				)
			)
		)
		(duplicate_pad_numbers_are_jumpers no)
		(fp_line
			(start 0.7874 -0.4064)
			(end 0.7874 0.4064)
			(stroke
				(width 0.1524)
				(type default)
			)
			(layer "F.SilkS")
		)
		(fp_line
			(start -0.7874 -0.4064)
			(end 0.7874 -0.4064)
			(stroke
				(width 0.1524)
				(type default)
			)
			(layer "F.SilkS")
		)
		(fp_line
			(start 0.7874 0.4064)
			(end -0.7874 0.4064)
			(stroke
				(width 0.1524)
				(type default)
			)
			(layer "F.SilkS")
		)
		(fp_line
			(start -0.7874 0.4064)
			(end -0.7874 -0.4064)
			(stroke
				(width 0.1524)
				(type default)
			)
			(layer "F.SilkS")
		)
		(fp_line
			(start -0.12065 -0.305054)
			(end -0.12065 -0.2794)
			(stroke
				(width 0.1)
				(type default)
			)
			(layer "F.Fab")
		)
		(fp_line
			(start -0.67945 -0.305054)
			(end -0.12065 -0.305054)
			(stroke
				(width 0.1)
				(type default)
			)
			(layer "F.Fab")
		)
		(fp_line
			(start 0.67945 -0.3048)
			(end 0.67945 0.3048)
			(stroke
				(width 0.1)
				(type default)
			)
			(layer "F.Fab")
		)
		(fp_line
			(start 0.12065 -0.3048)
			(end 0.67945 -0.3048)
			(stroke
				(width 0.1)
				(type default)
			)
			(layer "F.Fab")
		)
		(fp_line
			(start 0.12065 -0.2794)
			(end 0.12065 -0.3048)
			(stroke
				(width 0.1)
				(type default)
			)
			(layer "F.Fab")
		)
		(fp_line
			(start -0.12065 -0.2794)
			(end 0.12065 -0.2794)
			(stroke
				(width 0.1)
				(type default)
			)
			(layer "F.Fab")
		)
		(fp_line
			(start 0.120396 0.2794)
			(end -0.12065 0.2794)
			(stroke
				(width 0.1)
				(type default)
			)
			(layer "F.Fab")
		)
		(fp_line
			(start -0.12065 0.2794)
			(end -0.12065 0.3048)
			(stroke
				(width 0.1)
				(type default)
			)
			(layer "F.Fab")
		)
		(fp_line
			(start 0.67945 0.3048)
			(end 0.120396 0.3048)
			(stroke
				(width 0.1)
				(type default)
			)
			(layer "F.Fab")
		)
		(fp_line
			(start 0.120396 0.3048)
			(end 0.120396 0.2794)
			(stroke
				(width 0.1)
				(type default)
			)
			(layer "F.Fab")
		)
		(fp_line
			(start -0.12065 0.3048)
			(end -0.67945 0.3048)
			(stroke
				(width 0.1)
				(type default)
			)
			(layer "F.Fab")
		)
		(fp_line
			(start -0.67945 0.3048)
			(end -0.67945 -0.305054)
			(stroke
				(width 0.1)
				(type default)
			)
			(layer "F.Fab")
		)
		(pad "1" smd circle
			(at -0.40005 0 90)
			(size 0 0)
			(layers "F.Cu" "F.Mask" "F.Paste")
			(net "SW_P5V_AUX_BST")
		)
		(pad "2" smd circle
			(at 0.40005 0 90)
			(size 0 0)
			(layers "F.Cu" "F.Mask" "F.Paste")
			(net "SW_P5V_AUX_SW")
		)
	)
	(footprint ""
		(layer "F.Cu")
		(at 461.342232 -51.696366 -90)
		(property "Reference" "PR8389"
			(at 0 0 270)
			(layer "F.SilkS")
			(hide yes)
			(effects
				(font
					(size 1.27 1.27)
				)
			)
		)
		(property "Value" ""
			(at 0 0 270)
			(layer "F.Fab")
			(effects
				(font
					(size 1.27 1.27)
				)
			)
		)
		(duplicate_pad_numbers_are_jumpers no)
		(fp_line
			(start -0.7874 0.4064)
			(end -0.7874 -0.4064)
			(stroke
				(width 0.1524)
				(type default)
			)
			(layer "F.SilkS")
		)
		(fp_line
			(start 0.7874 0.4064)
			(end -0.7874 0.4064)
			(stroke
				(width 0.1524)
				(type default)
			)
			(layer "F.SilkS")
		)
		(fp_line
			(start -0.7874 -0.4064)
			(end 0.7874 -0.4064)
			(stroke
				(width 0.1524)
				(type default)
			)
			(layer "F.SilkS")
		)
		(fp_line
			(start 0.7874 -0.4064)
			(end 0.7874 0.4064)
			(stroke
				(width 0.1524)
				(type default)
			)
			(layer "F.SilkS")
		)
		(fp_line
			(start -0.67945 0.3048)
			(end -0.67945 -0.305054)
			(stroke
				(width 0.1)
				(type default)
			)
			(layer "F.Fab")
		)
		(fp_line
			(start -0.12065 0.3048)
			(end -0.67945 0.3048)
			(stroke
				(width 0.1)
				(type default)
			)
			(layer "F.Fab")
		)
		(fp_line
			(start 0.120396 0.3048)
			(end 0.120396 0.2794)
			(stroke
				(width 0.1)
				(type default)
			)
			(layer "F.Fab")
		)
		(fp_line
			(start 0.67945 0.3048)
			(end 0.120396 0.3048)
			(stroke
				(width 0.1)
				(type default)
			)
			(layer "F.Fab")
		)
		(fp_line
			(start -0.12065 0.2794)
			(end -0.12065 0.3048)
			(stroke
				(width 0.1)
				(type default)
			)
			(layer "F.Fab")
		)
		(fp_line
			(start 0.120396 0.2794)
			(end -0.12065 0.2794)
			(stroke
				(width 0.1)
				(type default)
			)
			(layer "F.Fab")
		)
		(fp_line
			(start -0.12065 -0.2794)
			(end 0.12065 -0.2794)
			(stroke
				(width 0.1)
				(type default)
			)
			(layer "F.Fab")
		)
		(fp_line
			(start 0.12065 -0.2794)
			(end 0.12065 -0.3048)
			(stroke
				(width 0.1)
				(type default)
			)
			(layer "F.Fab")
		)
		(fp_line
			(start 0.12065 -0.3048)
			(end 0.67945 -0.3048)
			(stroke
				(width 0.1)
				(type default)
			)
			(layer "F.Fab")
		)
		(fp_line
			(start 0.67945 -0.3048)
			(end 0.67945 0.3048)
			(stroke
				(width 0.1)
				(type default)
			)
			(layer "F.Fab")
		)
		(fp_line
			(start -0.67945 -0.305054)
			(end -0.12065 -0.305054)
			(stroke
				(width 0.1)
				(type default)
			)
			(layer "F.Fab")
		)
		(fp_line
			(start -0.12065 -0.305054)
			(end -0.12065 -0.2794)
			(stroke
				(width 0.1)
				(type default)
			)
			(layer "F.Fab")
		)
		(pad "1" smd circle
			(at -0.40005 0 270)
			(size 0 0)
			(layers "F.Cu" "F.Mask" "F.Paste")
			(net "P3V3_AUX_VDRV")
		)
		(pad "2" smd circle
			(at 0.40005 0 270)
			(size 0 0)
			(layers "F.Cu" "F.Mask" "F.Paste")
			(net "P3V3_AUX_VCC")
		)
	)
)
